#ISCELL
  mstr_misc dns *
  *
#ISCELL
  pure_quanta quanta_title_block_c *
  *
#ISCELL
  pure_quanta_power gnd *
  page165_i1
#ISCELL
  pure_quanta_power gnd *
  page165_i10
#CELL
  pure_quanta q_res *
  page165_i11
#ISCELL
  pure_quanta_power gnd *
  page165_i12
#CELL
  pure_quanta q_res *
  page165_i13
#ISCELL
  pure_quanta_power gnd *
  page165_i14
#CELL
  pure_quanta q_res *
  page165_i15
#ISCELL
  pure_quanta_power gnd *
  page165_i16
#CELL
  pure_quanta q_cap *
  page165_i17
#CELL
  pure_quanta q_res *
  page165_i18
#ISCELL
  pure_quanta_power gnd *
  page165_i19
#CELL
  pure_quanta q_res *
  page165_i2
#CELL
  pure_quanta q_cap *
  page165_i20
#CELL
  pure_quanta ncp3284amntxg *
  page165_i21
#ISCELL
  pure_quanta_power gnd *
  page165_i22
#CELL
  pure_quanta q_cap *
  page165_i23
#ISCELL
  pure_quanta_power universal_power *
  page165_i24
#CELL
  pure_quanta q_inductor *
  page165_i25
#CELL
  pure_quanta q_cap *
  page165_i26
#ISCELL
  pure_quanta_power gnd *
  page165_i27
#CELL
  pure_quanta q_capp *
  page165_i28
#CELL
  pure_quanta q_cap *
  page165_i29
#ISCELL
  pure_quanta_power gnd *
  page165_i3
#CELL
  pure_quanta q_cap *
  page165_i30
#CELL
  pure_quanta q_capp *
  page165_i31
#CELL
  pure_quanta q_cap *
  page165_i32
#CELL
  pure_quanta q_cap *
  page165_i33
#CELL
  pure_quanta q_cap *
  page165_i34
#CELL
  pure_quanta q_cap *
  page165_i35
#CELL
  pure_quanta q_cap *
  page165_i36
#CELL
  pure_quanta q_cap *
  page165_i37
#CELL
  pure_quanta q_cap *
  page165_i38
#CELL
  pure_quanta q_cap *
  page165_i39
#CELL
  pure_quanta q_res *
  page165_i4
#CELL
  pure_quanta q_cap *
  page165_i40
#CELL
  pure_quanta q_cap *
  page165_i41
#ISCELL
  pure_quanta_power gnd *
  page165_i42
#CELL
  pure_quanta q_cap *
  page165_i43
#ISCELL
  pure_quanta_power universal_power *
  page165_i44
#ISCELL
  pure_quanta_power gnd *
  page165_i45
#ISCELL
  pure_quanta_power gnd *
  page165_i46
#CELL
  pure_quanta q_res *
  page165_i47
#CELL
  pure_quanta q_cap *
  page165_i48
#CELL
  pure_quanta q_res *
  page165_i49
#ISCELL
  standard offpage *
  page165_i5
#ISCELL
  pure_quanta_power gnd *
  page165_i50
#CELL
  pure_quanta q_res *
  page165_i51
#ISCELL
  pure_quanta_power universal_power *
  page165_i52
#CELL
  pure_quanta q_inductor *
  page165_i53
#ISCELL
  standard offpage *
  page165_i54
#CELL
  pure_quanta q_capp *
  page165_i55
#CELL
  pure_quanta q_cap *
  page165_i56
#CELL
  pure_quanta q_res *
  page165_i57
#CELL
  pure_quanta q_capp *
  page165_i58
#CELL
  pure_quanta q_cap *
  page165_i59
#ISCELL
  pure_quanta_power p1v0_aux *
  page165_i6
#ISCELL
  pure_quanta_power gnd *
  page165_i60
#CELL
  pure_quanta q_cap *
  page165_i61
#CELL
  pure_quanta q_cap *
  page165_i62
#CELL
  pure_quanta q_cap *
  page165_i63
#ISCELL
  pure_quanta_power universal_power *
  page165_i64
#CELL
  pure_quanta q_res *
  page165_i65
#ISCELL
  pure_quanta_power universal_power *
  page165_i66
#ISCELL
  pure_quanta_power gnd *
  page165_i7
#CELL
  pure_quanta q_cap *
  page165_i8
#CELL
  pure_quanta q_res *
  page165_i9
